(kicad_pcb
	(version 20260206)
	(generator "pcbnew")
	(generator_version "10.0")
	(general
		(thickness 1.6)
		(legacy_teardrops no)
	)
	(paper "A4")
	(title_block
		(title "03242023_DA0F0TMBIJ0_F0T_Motherboard_J_brd_V01_OCP.brd")
		(comment 1 "Grand Teton / footprints 1136-1141 of 6105")
	)
	(layers
		(0 "F.Cu" signal "TOP")
		(4 "In1.Cu" signal "GND")
		(6 "In2.Cu" signal "IN1")
		(8 "In3.Cu" signal "GND1")
		(10 "In4.Cu" signal "IN2")
		(12 "In5.Cu" signal "GND2")
		(14 "In6.Cu" signal "IN3")
		(16 "In7.Cu" signal "GND3")
		(18 "In8.Cu" signal "VCC")
		(20 "In9.Cu" signal "VCC1")
		(22 "In10.Cu" signal "GND4")
		(24 "In11.Cu" signal "IN4")
		(26 "In12.Cu" signal "GND5")
		(28 "In13.Cu" signal "IN5")
		(30 "In14.Cu" signal "GND6")
		(32 "In15.Cu" signal "IN6")
		(34 "In16.Cu" signal "GND7")
		(2 "B.Cu" signal "BOTTOM")
		(9 "F.Adhes" user "F.Adhesive")
		(11 "B.Adhes" user "B.Adhesive")
		(13 "F.Paste" user "Package Geometry/Pastemask Top")
		(15 "B.Paste" user "Package Geometry/Pastemask Bottom")
		(5 "F.SilkS" user "Ref Des/Silkscreen Top")
		(7 "B.SilkS" user "Ref Des/Silkscreen Bottom")
		(1 "F.Mask" user "Board Geometry/Soldermask Top")
		(3 "B.Mask" user "Board Geometry/Soldermask Bottom")
		(17 "Dwgs.User" user "User.Drawings")
		(19 "Cmts.User" user "User.Comments")
		(21 "Eco1.User" user "User.Eco1")
		(23 "Eco2.User" user "User.Eco2")
		(25 "Edge.Cuts" user "Board Geometry/Outline")
		(27 "Margin" user)
		(31 "F.CrtYd" user "Package Geometry/Place Bound Top")
		(29 "B.CrtYd" user "Package Geometry/Place Bound Bottom")
		(35 "F.Fab" user "Ref Des/Assembly Top")
		(33 "B.Fab" user "Ref Des/Assembly Bottom")
	)
	(footprint ""
		(layer "F.Cu")
		(at 149.987 -131.282948 180)
		(property "Reference" "Q144"
			(at 1.15824 -2.07391 0)
			(unlocked yes)
			(layer "F.SilkS")
			(effects
				(font
					(size 0.7874 0.5842)
					(thickness 0.1524)
				)
				(justify left)
			)
		)
		(property "Value" ""
			(at 0 0 180)
			(layer "F.Fab")
			(effects
				(font
					(size 1.27 1.27)
				)
			)
		)
		(duplicate_pad_numbers_are_jumpers no)
		(fp_line
			(start 1.332738 1.100074)
			(end -1.332738 1.100074)
			(stroke
				(width 0.1524)
				(type default)
			)
			(layer "F.SilkS")
		)
		(fp_line
			(start 1.332738 -1.100074)
			(end 1.332738 1.100074)
			(stroke
				(width 0.1524)
				(type default)
			)
			(layer "F.SilkS")
		)
		(fp_line
			(start 0.4826 -1.100074)
			(end 1.332738 -1.100074)
			(stroke
				(width 0.1524)
				(type default)
			)
			(layer "F.SilkS")
		)
		(fp_line
			(start 0 -0.541274)
			(end 0.4826 -1.100074)
			(stroke
				(width 0.1524)
				(type default)
			)
			(layer "F.SilkS")
		)
		(fp_line
			(start -0.4826 -1.100074)
			(end 0 -0.541274)
			(stroke
				(width 0.1524)
				(type default)
			)
			(layer "F.SilkS")
		)
		(fp_line
			(start -1.332738 1.100074)
			(end -1.332738 -1.100074)
			(stroke
				(width 0.1524)
				(type default)
			)
			(layer "F.SilkS")
		)
		(fp_line
			(start -1.332738 -1.100074)
			(end -0.4826 -1.100074)
			(stroke
				(width 0.1524)
				(type default)
			)
			(layer "F.SilkS")
		)
		(fp_poly
			(pts
				(xy -2.05486 -0.910844) (xy -1.533144 -0.649986) (xy -2.05486 -0.389128)
			)
			(stroke
				(width 0)
				(type default)
			)
			(fill yes)
			(layer "F.SilkS")
		)
		(fp_line
			(start 0.674878 1.100074)
			(end -0.674878 1.100074)
			(stroke
				(width 0.1)
				(type default)
			)
			(layer "F.Fab")
		)
		(fp_line
			(start 0.674878 -1.100074)
			(end 0.674878 1.100074)
			(stroke
				(width 0.1)
				(type default)
			)
			(layer "F.Fab")
		)
		(fp_line
			(start -0.674878 1.100074)
			(end -0.674878 -1.100074)
			(stroke
				(width 0.1)
				(type default)
			)
			(layer "F.Fab")
		)
		(fp_line
			(start -0.674878 -1.100074)
			(end 0.674878 -1.100074)
			(stroke
				(width 0.1)
				(type default)
			)
			(layer "F.Fab")
		)
		(fp_poly
			(pts
				(xy -2.2352 -0.298958) (xy -2.2352 -1.001014) (xy -1.533144 -0.649986)
			)
			(stroke
				(width 0)
				(type default)
			)
			(fill yes)
			(layer "F.Fab")
		)
		(pad "1" smd rect
			(at -0.94996 -0.649986 270)
			(size 0.4318 0.508)
			(layers "F.Cu" "F.Mask" "F.Paste")
			(net "GND")
		)
		(pad "2" smd rect
			(at -0.94996 0 270)
			(size 0.4318 0.508)
			(layers "F.Cu" "F.Mask" "F.Paste")
			(net "PWRGD_PS_PWROK_PLD")
		)
		(pad "3" smd rect
			(at -0.94996 0.649986 270)
			(size 0.4318 0.508)
			(layers "F.Cu" "F.Mask" "F.Paste")
			(net "PWRGD_PS_PWROK_PLD_ISO")
		)
		(pad "4" smd rect
			(at 0.94996 0.649986 270)
			(size 0.4318 0.508)
			(layers "F.Cu" "F.Mask" "F.Paste")
			(net "GND")
		)
		(pad "5" smd rect
			(at 0.94996 0 270)
			(size 0.4318 0.508)
			(layers "F.Cu" "F.Mask" "F.Paste")
			(net "PWRGD_PS_PWROK_PLD_N")
		)
		(pad "6" smd rect
			(at 0.94996 -0.649986 270)
			(size 0.4318 0.508)
			(layers "F.Cu" "F.Mask" "F.Paste")
			(net "PWRGD_PS_PWROK_PLD_N")
		)
	)
	(footprint ""
		(layer "F.Cu")
		(at 46.582584 -108.047282 180)
		(property "Reference" "R2908"
			(at 0 0 180)
			(layer "F.SilkS")
			(hide yes)
			(effects
				(font
					(size 1.27 1.27)
				)
			)
		)
		(property "Value" ""
			(at 0 0 180)
			(layer "F.Fab")
			(effects
				(font
					(size 1.27 1.27)
				)
			)
		)
		(duplicate_pad_numbers_are_jumpers no)
		(fp_line
			(start 0.7874 0.4064)
			(end -0.7874 0.4064)
			(stroke
				(width 0.1524)
				(type default)
			)
			(layer "F.SilkS")
		)
		(fp_line
			(start 0.7874 -0.4064)
			(end 0.7874 0.4064)
			(stroke
				(width 0.1524)
				(type default)
			)
			(layer "F.SilkS")
		)
		(fp_line
			(start -0.7874 0.4064)
			(end -0.7874 -0.4064)
			(stroke
				(width 0.1524)
				(type default)
			)
			(layer "F.SilkS")
		)
		(fp_line
			(start -0.7874 -0.4064)
			(end 0.7874 -0.4064)
			(stroke
				(width 0.1524)
				(type default)
			)
			(layer "F.SilkS")
		)
		(fp_line
			(start 0.67945 0.3048)
			(end 0.120396 0.3048)
			(stroke
				(width 0.1)
				(type default)
			)
			(layer "F.Fab")
		)
		(fp_line
			(start 0.67945 -0.3048)
			(end 0.67945 0.3048)
			(stroke
				(width 0.1)
				(type default)
			)
			(layer "F.Fab")
		)
		(fp_line
			(start 0.12065 -0.2794)
			(end 0.12065 -0.3048)
			(stroke
				(width 0.1)
				(type default)
			)
			(layer "F.Fab")
		)
		(fp_line
			(start 0.12065 -0.3048)
			(end 0.67945 -0.3048)
			(stroke
				(width 0.1)
				(type default)
			)
			(layer "F.Fab")
		)
		(fp_line
			(start 0.120396 0.3048)
			(end 0.120396 0.2794)
			(stroke
				(width 0.1)
				(type default)
			)
			(layer "F.Fab")
		)
		(fp_line
			(start 0.120396 0.2794)
			(end -0.12065 0.2794)
			(stroke
				(width 0.1)
				(type default)
			)
			(layer "F.Fab")
		)
		(fp_line
			(start -0.12065 0.3048)
			(end -0.67945 0.3048)
			(stroke
				(width 0.1)
				(type default)
			)
			(layer "F.Fab")
		)
		(fp_line
			(start -0.12065 0.2794)
			(end -0.12065 0.3048)
			(stroke
				(width 0.1)
				(type default)
			)
			(layer "F.Fab")
		)
		(fp_line
			(start -0.12065 -0.2794)
			(end 0.12065 -0.2794)
			(stroke
				(width 0.1)
				(type default)
			)
			(layer "F.Fab")
		)
		(fp_line
			(start -0.12065 -0.305054)
			(end -0.12065 -0.2794)
			(stroke
				(width 0.1)
				(type default)
			)
			(layer "F.Fab")
		)
		(fp_line
			(start -0.67945 0.3048)
			(end -0.67945 -0.305054)
			(stroke
				(width 0.1)
				(type default)
			)
			(layer "F.Fab")
		)
		(fp_line
			(start -0.67945 -0.305054)
			(end -0.12065 -0.305054)
			(stroke
				(width 0.1)
				(type default)
			)
			(layer "F.Fab")
		)
		(pad "1" smd circle
			(at -0.40005 0 180)
			(size 0 0)
			(layers "F.Cu" "F.Mask" "F.Paste")
			(net "P3V3")
		)
		(pad "2" smd circle
			(at 0.40005 0 180)
			(size 0 0)
			(layers "F.Cu" "F.Mask" "F.Paste")
			(net "P3V3_ADC")
		)
	)
	(footprint ""
		(layer "F.Cu")
		(at 174.82566 -97.516188 90)
		(property "Reference" "R1330"
			(at 0 0 90)
			(layer "F.SilkS")
			(hide yes)
			(effects
				(font
					(size 1.27 1.27)
				)
			)
		)
		(property "Value" ""
			(at 0 0 90)
			(layer "F.Fab")
			(effects
				(font
					(size 1.27 1.27)
				)
			)
		)
		(duplicate_pad_numbers_are_jumpers no)
		(fp_line
			(start 0.7874 -0.4064)
			(end 0.7874 0.4064)
			(stroke
				(width 0.1524)
				(type default)
			)
			(layer "F.SilkS")
		)
		(fp_line
			(start -0.7874 -0.4064)
			(end 0.7874 -0.4064)
			(stroke
				(width 0.1524)
				(type default)
			)
			(layer "F.SilkS")
		)
		(fp_line
			(start 0.7874 0.4064)
			(end -0.7874 0.4064)
			(stroke
				(width 0.1524)
				(type default)
			)
			(layer "F.SilkS")
		)
		(fp_line
			(start -0.7874 0.4064)
			(end -0.7874 -0.4064)
			(stroke
				(width 0.1524)
				(type default)
			)
			(layer "F.SilkS")
		)
		(fp_line
			(start -0.12065 -0.305054)
			(end -0.12065 -0.2794)
			(stroke
				(width 0.1)
				(type default)
			)
			(layer "F.Fab")
		)
		(fp_line
			(start -0.67945 -0.305054)
			(end -0.12065 -0.305054)
			(stroke
				(width 0.1)
				(type default)
			)
			(layer "F.Fab")
		)
		(fp_line
			(start 0.67945 -0.3048)
			(end 0.67945 0.3048)
			(stroke
				(width 0.1)
				(type default)
			)
			(layer "F.Fab")
		)
		(fp_line
			(start 0.12065 -0.3048)
			(end 0.67945 -0.3048)
			(stroke
				(width 0.1)
				(type default)
			)
			(layer "F.Fab")
		)
		(fp_line
			(start 0.12065 -0.2794)
			(end 0.12065 -0.3048)
			(stroke
				(width 0.1)
				(type default)
			)
			(layer "F.Fab")
		)
		(fp_line
			(start -0.12065 -0.2794)
			(end 0.12065 -0.2794)
			(stroke
				(width 0.1)
				(type default)
			)
			(layer "F.Fab")
		)
		(fp_line
			(start 0.120396 0.2794)
			(end -0.12065 0.2794)
			(stroke
				(width 0.1)
				(type default)
			)
			(layer "F.Fab")
		)
		(fp_line
			(start -0.12065 0.2794)
			(end -0.12065 0.3048)
			(stroke
				(width 0.1)
				(type default)
			)
			(layer "F.Fab")
		)
		(fp_line
			(start 0.67945 0.3048)
			(end 0.120396 0.3048)
			(stroke
				(width 0.1)
				(type default)
			)
			(layer "F.Fab")
		)
		(fp_line
			(start 0.120396 0.3048)
			(end 0.120396 0.2794)
			(stroke
				(width 0.1)
				(type default)
			)
			(layer "F.Fab")
		)
		(fp_line
			(start -0.12065 0.3048)
			(end -0.67945 0.3048)
			(stroke
				(width 0.1)
				(type default)
			)
			(layer "F.Fab")
		)
		(fp_line
			(start -0.67945 0.3048)
			(end -0.67945 -0.305054)
			(stroke
				(width 0.1)
				(type default)
			)
			(layer "F.Fab")
		)
		(pad "1" smd circle
			(at -0.40005 0 90)
			(size 0 0)
			(layers "F.Cu" "F.Mask" "F.Paste")
			(net "PWRGD_DRAMPWRGD_CPU1_CD_R_LVC1")
		)
		(pad "2" smd circle
			(at 0.40005 0 90)
			(size 0 0)
			(layers "F.Cu" "F.Mask" "F.Paste")
			(net "GND")
		)
	)
	(footprint ""
		(layer "F.Cu")
		(at 374.00484 -336.935572 -90)
		(property "Reference" "PC251_P0_5"
			(at 0 0 270)
			(layer "F.SilkS")
			(hide yes)
			(effects
				(font
					(size 1.27 1.27)
				)
			)
		)
		(property "Value" ""
			(at 0 0 270)
			(layer "F.Fab")
			(effects
				(font
					(size 1.27 1.27)
				)
			)
		)
		(duplicate_pad_numbers_are_jumpers no)
		(fp_line
			(start -0.7874 0.4064)
			(end -0.7874 -0.4064)
			(stroke
				(width 0.1524)
				(type default)
			)
			(layer "F.SilkS")
		)
		(fp_line
			(start 0.7874 0.4064)
			(end -0.7874 0.4064)
			(stroke
				(width 0.1524)
				(type default)
			)
			(layer "F.SilkS")
		)
		(fp_line
			(start -0.7874 -0.4064)
			(end 0.7874 -0.4064)
			(stroke
				(width 0.1524)
				(type default)
			)
			(layer "F.SilkS")
		)
		(fp_line
			(start 0.7874 -0.4064)
			(end 0.7874 0.4064)
			(stroke
				(width 0.1524)
				(type default)
			)
			(layer "F.SilkS")
		)
		(fp_line
			(start -0.67945 0.3048)
			(end -0.67945 -0.305054)
			(stroke
				(width 0.1)
				(type default)
			)
			(layer "F.Fab")
		)
		(fp_line
			(start -0.12065 0.3048)
			(end -0.67945 0.3048)
			(stroke
				(width 0.1)
				(type default)
			)
			(layer "F.Fab")
		)
		(fp_line
			(start 0.120396 0.3048)
			(end 0.120396 0.2794)
			(stroke
				(width 0.1)
				(type default)
			)
			(layer "F.Fab")
		)
		(fp_line
			(start 0.67945 0.3048)
			(end 0.120396 0.3048)
			(stroke
				(width 0.1)
				(type default)
			)
			(layer "F.Fab")
		)
		(fp_line
			(start -0.12065 0.2794)
			(end -0.12065 0.3048)
			(stroke
				(width 0.1)
				(type default)
			)
			(layer "F.Fab")
		)
		(fp_line
			(start 0.120396 0.2794)
			(end -0.12065 0.2794)
			(stroke
				(width 0.1)
				(type default)
			)
			(layer "F.Fab")
		)
		(fp_line
			(start -0.12065 -0.2794)
			(end 0.12065 -0.2794)
			(stroke
				(width 0.1)
				(type default)
			)
			(layer "F.Fab")
		)
		(fp_line
			(start 0.12065 -0.2794)
			(end 0.12065 -0.3048)
			(stroke
				(width 0.1)
				(type default)
			)
			(layer "F.Fab")
		)
		(fp_line
			(start 0.12065 -0.3048)
			(end 0.67945 -0.3048)
			(stroke
				(width 0.1)
				(type default)
			)
			(layer "F.Fab")
		)
		(fp_line
			(start 0.67945 -0.3048)
			(end 0.67945 0.3048)
			(stroke
				(width 0.1)
				(type default)
			)
			(layer "F.Fab")
		)
		(fp_line
			(start -0.67945 -0.305054)
			(end -0.12065 -0.305054)
			(stroke
				(width 0.1)
				(type default)
			)
			(layer "F.Fab")
		)
		(fp_line
			(start -0.12065 -0.305054)
			(end -0.12065 -0.2794)
			(stroke
				(width 0.1)
				(type default)
			)
			(layer "F.Fab")
		)
		(pad "1" smd circle
			(at -0.40005 0 270)
			(size 0 0)
			(layers "F.Cu" "F.Mask" "F.Paste")
			(net "PVCCIN_CPU0_PVCC")
		)
		(pad "2" smd circle
			(at 0.40005 0 270)
			(size 0 0)
			(layers "F.Cu" "F.Mask" "F.Paste")
			(net "GND")
		)
	)
	(footprint ""
		(layer "F.Cu")
		(at 148.197824 -51.404012)
		(property "Reference" "R3611"
			(at 0 0 0)
			(layer "F.SilkS")
			(hide yes)
			(effects
				(font
					(size 1.27 1.27)
				)
			)
		)
		(property "Value" ""
			(at 0 0 0)
			(layer "F.Fab")
			(effects
				(font
					(size 1.27 1.27)
				)
			)
		)
		(duplicate_pad_numbers_are_jumpers no)
		(fp_line
			(start -0.7874 -0.4064)
			(end 0.7874 -0.4064)
			(stroke
				(width 0.1524)
				(type default)
			)
			(layer "F.SilkS")
		)
		(fp_line
			(start -0.7874 0.4064)
			(end -0.7874 -0.4064)
			(stroke
				(width 0.1524)
				(type default)
			)
			(layer "F.SilkS")
		)
		(fp_line
			(start 0.7874 -0.4064)
			(end 0.7874 0.4064)
			(stroke
				(width 0.1524)
				(type default)
			)
			(layer "F.SilkS")
		)
		(fp_line
			(start 0.7874 0.4064)
			(end -0.7874 0.4064)
			(stroke
				(width 0.1524)
				(type default)
			)
			(layer "F.SilkS")
		)
		(fp_line
			(start -0.67945 -0.305054)
			(end -0.12065 -0.305054)
			(stroke
				(width 0.1)
				(type default)
			)
			(layer "F.Fab")
		)
		(fp_line
			(start -0.67945 0.3048)
			(end -0.67945 -0.305054)
			(stroke
				(width 0.1)
				(type default)
			)
			(layer "F.Fab")
		)
		(fp_line
			(start -0.12065 -0.305054)
			(end -0.12065 -0.2794)
			(stroke
				(width 0.1)
				(type default)
			)
			(layer "F.Fab")
		)
		(fp_line
			(start -0.12065 -0.2794)
			(end 0.12065 -0.2794)
			(stroke
				(width 0.1)
				(type default)
			)
			(layer "F.Fab")
		)
		(fp_line
			(start -0.12065 0.2794)
			(end -0.12065 0.3048)
			(stroke
				(width 0.1)
				(type default)
			)
			(layer "F.Fab")
		)
		(fp_line
			(start -0.12065 0.3048)
			(end -0.67945 0.3048)
			(stroke
				(width 0.1)
				(type default)
			)
			(layer "F.Fab")
		)
		(fp_line
			(start 0.120396 0.2794)
			(end -0.12065 0.2794)
			(stroke
				(width 0.1)
				(type default)
			)
			(layer "F.Fab")
		)
		(fp_line
			(start 0.120396 0.3048)
			(end 0.120396 0.2794)
			(stroke
				(width 0.1)
				(type default)
			)
			(layer "F.Fab")
		)
		(fp_line
			(start 0.12065 -0.3048)
			(end 0.67945 -0.3048)
			(stroke
				(width 0.1)
				(type default)
			)
			(layer "F.Fab")
		)
		(fp_line
			(start 0.12065 -0.2794)
			(end 0.12065 -0.3048)
			(stroke
				(width 0.1)
				(type default)
			)
			(layer "F.Fab")
		)
		(fp_line
			(start 0.67945 -0.3048)
			(end 0.67945 0.3048)
			(stroke
				(width 0.1)
				(type default)
			)
			(layer "F.Fab")
		)
		(fp_line
			(start 0.67945 0.3048)
			(end 0.120396 0.3048)
			(stroke
				(width 0.1)
				(type default)
			)
			(layer "F.Fab")
		)
		(pad "1" smd circle
			(at -0.40005 0)
			(size 0 0)
			(layers "F.Cu" "F.Mask" "F.Paste")
			(net "GND")
		)
		(pad "2" smd circle
			(at 0.40005 0)
			(size 0 0)
			(layers "F.Cu" "F.Mask" "F.Paste")
			(net "INA230_4_A0")
		)
	)
	(footprint ""
		(layer "F.Cu")
		(at 176.17948 -422.366948 180)
		(property "Reference" "R2911"
			(at 0 0 180)
			(layer "F.SilkS")
			(hide yes)
			(effects
				(font
					(size 1.27 1.27)
				)
			)
		)
		(property "Value" ""
			(at 0 0 180)
			(layer "F.Fab")
			(effects
				(font
					(size 1.27 1.27)
				)
			)
		)
		(duplicate_pad_numbers_are_jumpers no)
		(fp_line
			(start 0.7874 0.4064)
			(end -0.7874 0.4064)
			(stroke
				(width 0.1524)
				(type default)
			)
			(layer "F.SilkS")
		)
		(fp_line
			(start 0.7874 -0.4064)
			(end 0.7874 0.4064)
			(stroke
				(width 0.1524)
				(type default)
			)
			(layer "F.SilkS")
		)
		(fp_line
			(start -0.7874 0.4064)
			(end -0.7874 -0.4064)
			(stroke
				(width 0.1524)
				(type default)
			)
			(layer "F.SilkS")
		)
		(fp_line
			(start -0.7874 -0.4064)
			(end 0.7874 -0.4064)
			(stroke
				(width 0.1524)
				(type default)
			)
			(layer "F.SilkS")
		)
		(fp_line
			(start 0.67945 0.3048)
			(end 0.120396 0.3048)
			(stroke
				(width 0.1)
				(type default)
			)
			(layer "F.Fab")
		)
		(fp_line
			(start 0.67945 -0.3048)
			(end 0.67945 0.3048)
			(stroke
				(width 0.1)
				(type default)
			)
			(layer "F.Fab")
		)
		(fp_line
			(start 0.12065 -0.2794)
			(end 0.12065 -0.3048)
			(stroke
				(width 0.1)
				(type default)
			)
			(layer "F.Fab")
		)
		(fp_line
			(start 0.12065 -0.3048)
			(end 0.67945 -0.3048)
			(stroke
				(width 0.1)
				(type default)
			)
			(layer "F.Fab")
		)
		(fp_line
			(start 0.120396 0.3048)
			(end 0.120396 0.2794)
			(stroke
				(width 0.1)
				(type default)
			)
			(layer "F.Fab")
		)
		(fp_line
			(start 0.120396 0.2794)
			(end -0.12065 0.2794)
			(stroke
				(width 0.1)
				(type default)
			)
			(layer "F.Fab")
		)
		(fp_line
			(start -0.12065 0.3048)
			(end -0.67945 0.3048)
			(stroke
				(width 0.1)
				(type default)
			)
			(layer "F.Fab")
		)
		(fp_line
			(start -0.12065 0.2794)
			(end -0.12065 0.3048)
			(stroke
				(width 0.1)
				(type default)
			)
			(layer "F.Fab")
		)
		(fp_line
			(start -0.12065 -0.2794)
			(end 0.12065 -0.2794)
			(stroke
				(width 0.1)
				(type default)
			)
			(layer "F.Fab")
		)
		(fp_line
			(start -0.12065 -0.305054)
			(end -0.12065 -0.2794)
			(stroke
				(width 0.1)
				(type default)
			)
			(layer "F.Fab")
		)
		(fp_line
			(start -0.67945 0.3048)
			(end -0.67945 -0.305054)
			(stroke
				(width 0.1)
				(type default)
			)
			(layer "F.Fab")
		)
		(fp_line
			(start -0.67945 -0.305054)
			(end -0.12065 -0.305054)
			(stroke
				(width 0.1)
				(type default)
			)
			(layer "F.Fab")
		)
		(pad "1" smd circle
			(at -0.40005 0 180)
			(size 0 0)
			(layers "F.Cu" "F.Mask" "F.Paste")
			(net "P3V3_AUX")
		)
		(pad "2" smd circle
			(at 0.40005 0 180)
			(size 0 0)
			(layers "F.Cu" "F.Mask" "F.Paste")
			(net "RST_SWB_BIC_BUF_R_N")
		)
	)
)
